# S9S_MB_2U (Grand Teton) — schematic netlist excerpt (pin names and nets, part order shuffled) for the footprints in the layout excerpt that follows; sources: Cadence DE-HDL packaged netlist, KiCad conversion of 03242023_DA0F0TMBIJ0_F0T_Motherboard_J_brd_V01_OCP.brd

R1195  Q_RES  130 1% CHIP  pkg 0402LF  page 218 : A = P3V3_AUX ; B = PU_PLD_HEARTBEAT_LVC3
R312  Q_RES  0 5% CHIP  pkg 0402LF  page 284 : A = SVID_ALERT0_CPU1_R_N ; B = SVID_ALERT_PVCCIN_CPU1_R

(kicad_pcb
	(version 20260206)
	(generator "pcbnew")
	(generator_version "10.0")
	(general
		(thickness 1.6)
		(legacy_teardrops no)
	)
	(paper "A4")
	(title_block
		(title "03242023_DA0F0TMBIJ0_F0T_Motherboard_J_brd_V01_OCP.brd")
		(comment 1 "Grand Teton / footprints 1022-1023 of 6105")
	)
	(layers
		(0 "F.Cu" signal "TOP")
		(4 "In1.Cu" signal "GND")
		(6 "In2.Cu" signal "IN1")
		(8 "In3.Cu" signal "GND1")
		(10 "In4.Cu" signal "IN2")
		(12 "In5.Cu" signal "GND2")
		(14 "In6.Cu" signal "IN3")
		(16 "In7.Cu" signal "GND3")
		(18 "In8.Cu" signal "VCC")
		(20 "In9.Cu" signal "VCC1")
		(22 "In10.Cu" signal "GND4")
		(24 "In11.Cu" signal "IN4")
		(26 "In12.Cu" signal "GND5")
		(28 "In13.Cu" signal "IN5")
		(30 "In14.Cu" signal "GND6")
		(32 "In15.Cu" signal "IN6")
		(34 "In16.Cu" signal "GND7")
		(2 "B.Cu" signal "BOTTOM")
		(9 "F.Adhes" user "F.Adhesive")
		(11 "B.Adhes" user "B.Adhesive")
		(13 "F.Paste" user "Package Geometry/Pastemask Top")
		(15 "B.Paste" user "Package Geometry/Pastemask Bottom")
		(5 "F.SilkS" user "Ref Des/Silkscreen Top")
		(7 "B.SilkS" user "Ref Des/Silkscreen Bottom")
		(1 "F.Mask" user "Board Geometry/Soldermask Top")
		(3 "B.Mask" user "Board Geometry/Soldermask Bottom")
		(17 "Dwgs.User" user "User.Drawings")
		(19 "Cmts.User" user "User.Comments")
		(21 "Eco1.User" user "User.Eco1")
		(23 "Eco2.User" user "User.Eco2")
		(25 "Edge.Cuts" user "Board Geometry/Outline")
		(27 "Margin" user)
		(31 "F.CrtYd" user "Package Geometry/Place Bound Top")
		(29 "B.CrtYd" user "Package Geometry/Place Bound Bottom")
		(35 "F.Fab" user "Ref Des/Assembly Top")
		(33 "B.Fab" user "Ref Des/Assembly Bottom")
	)
	(footprint ""
		(layer "F.Cu")
		(at 220.04528 -109.591348)
		(property "Reference" "R1195"
			(at 0 0 0)
			(layer "F.SilkS")
			(hide yes)
			(effects
				(font
					(size 1.27 1.27)
				)
			)
		)
		(property "Value" ""
			(at 0 0 0)
			(layer "F.Fab")
			(effects
				(font
					(size 1.27 1.27)
				)
			)
		)
		(duplicate_pad_numbers_are_jumpers no)
		(fp_line
			(start -0.7874 -0.4064)
			(end 0.7874 -0.4064)
			(stroke
				(width 0.1524)
				(type default)
			)
			(layer "F.SilkS")
		)
		(fp_line
			(start -0.7874 0.4064)
			(end -0.7874 -0.4064)
			(stroke
				(width 0.1524)
				(type default)
			)
			(layer "F.SilkS")
		)
		(fp_line
			(start 0.7874 -0.4064)
			(end 0.7874 0.4064)
			(stroke
				(width 0.1524)
				(type default)
			)
			(layer "F.SilkS")
		)
		(fp_line
			(start 0.7874 0.4064)
			(end -0.7874 0.4064)
			(stroke
				(width 0.1524)
				(type default)
			)
			(layer "F.SilkS")
		)
		(fp_line
			(start -0.67945 -0.305054)
			(end -0.12065 -0.305054)
			(stroke
				(width 0.1)
				(type default)
			)
			(layer "F.Fab")
		)
		(fp_line
			(start -0.67945 0.3048)
			(end -0.67945 -0.305054)
			(stroke
				(width 0.1)
				(type default)
			)
			(layer "F.Fab")
		)
		(fp_line
			(start -0.12065 -0.305054)
			(end -0.12065 -0.2794)
			(stroke
				(width 0.1)
				(type default)
			)
			(layer "F.Fab")
		)
		(fp_line
			(start -0.12065 -0.2794)
			(end 0.12065 -0.2794)
			(stroke
				(width 0.1)
				(type default)
			)
			(layer "F.Fab")
		)
		(fp_line
			(start -0.12065 0.2794)
			(end -0.12065 0.3048)
			(stroke
				(width 0.1)
				(type default)
			)
			(layer "F.Fab")
		)
		(fp_line
			(start -0.12065 0.3048)
			(end -0.67945 0.3048)
			(stroke
				(width 0.1)
				(type default)
			)
			(layer "F.Fab")
		)
		(fp_line
			(start 0.120396 0.2794)
			(end -0.12065 0.2794)
			(stroke
				(width 0.1)
				(type default)
			)
			(layer "F.Fab")
		)
		(fp_line
			(start 0.120396 0.3048)
			(end 0.120396 0.2794)
			(stroke
				(width 0.1)
				(type default)
			)
			(layer "F.Fab")
		)
		(fp_line
			(start 0.12065 -0.3048)
			(end 0.67945 -0.3048)
			(stroke
				(width 0.1)
				(type default)
			)
			(layer "F.Fab")
		)
		(fp_line
			(start 0.12065 -0.2794)
			(end 0.12065 -0.3048)
			(stroke
				(width 0.1)
				(type default)
			)
			(layer "F.Fab")
		)
		(fp_line
			(start 0.67945 -0.3048)
			(end 0.67945 0.3048)
			(stroke
				(width 0.1)
				(type default)
			)
			(layer "F.Fab")
		)
		(fp_line
			(start 0.67945 0.3048)
			(end 0.120396 0.3048)
			(stroke
				(width 0.1)
				(type default)
			)
			(layer "F.Fab")
		)
		(pad "1" smd circle
			(at -0.40005 0)
			(size 0 0)
			(layers "F.Cu" "F.Mask" "F.Paste")
			(net "P3V3_AUX")
		)
		(pad "2" smd circle
			(at 0.40005 0)
			(size 0 0)
			(layers "F.Cu" "F.Mask" "F.Paste")
			(net "PU_PLD_HEARTBEAT_LVC3")
		)
	)
	(footprint ""
		(layer "F.Cu")
		(at 102.845616 -355.773736)
		(property "Reference" "R312"
			(at 0 0 0)
			(layer "F.SilkS")
			(hide yes)
			(effects
				(font
					(size 1.27 1.27)
				)
			)
		)
		(property "Value" ""
			(at 0 0 0)
			(layer "F.Fab")
			(effects
				(font
					(size 1.27 1.27)
				)
			)
		)
		(duplicate_pad_numbers_are_jumpers no)
		(fp_line
			(start -0.7874 -0.4064)
			(end 0.7874 -0.4064)
			(stroke
				(width 0.1524)
				(type default)
			)
			(layer "F.SilkS")
		)
		(fp_line
			(start -0.7874 0.4064)
			(end -0.7874 -0.4064)
			(stroke
				(width 0.1524)
				(type default)
			)
			(layer "F.SilkS")
		)
		(fp_line
			(start 0.7874 -0.4064)
			(end 0.7874 0.4064)
			(stroke
				(width 0.1524)
				(type default)
			)
			(layer "F.SilkS")
		)
		(fp_line
			(start 0.7874 0.4064)
			(end -0.7874 0.4064)
			(stroke
				(width 0.1524)
				(type default)
			)
			(layer "F.SilkS")
		)
		(fp_line
			(start -0.67945 -0.305054)
			(end -0.12065 -0.305054)
			(stroke
				(width 0.1)
				(type default)
			)
			(layer "F.Fab")
		)
		(fp_line
			(start -0.67945 0.3048)
			(end -0.67945 -0.305054)
			(stroke
				(width 0.1)
				(type default)
			)
			(layer "F.Fab")
		)
		(fp_line
			(start -0.12065 -0.305054)
			(end -0.12065 -0.2794)
			(stroke
				(width 0.1)
				(type default)
			)
			(layer "F.Fab")
		)
		(fp_line
			(start -0.12065 -0.2794)
			(end 0.12065 -0.2794)
			(stroke
				(width 0.1)
				(type default)
			)
			(layer "F.Fab")
		)
		(fp_line
			(start -0.12065 0.2794)
			(end -0.12065 0.3048)
			(stroke
				(width 0.1)
				(type default)
			)
			(layer "F.Fab")
		)
		(fp_line
			(start -0.12065 0.3048)
			(end -0.67945 0.3048)
			(stroke
				(width 0.1)
				(type default)
			)
			(layer "F.Fab")
		)
		(fp_line
			(start 0.120396 0.2794)
			(end -0.12065 0.2794)
			(stroke
				(width 0.1)
				(type default)
			)
			(layer "F.Fab")
		)
		(fp_line
			(start 0.120396 0.3048)
			(end 0.120396 0.2794)
			(stroke
				(width 0.1)
				(type default)
			)
			(layer "F.Fab")
		)
		(fp_line
			(start 0.12065 -0.3048)
			(end 0.67945 -0.3048)
			(stroke
				(width 0.1)
				(type default)
			)
			(layer "F.Fab")
		)
		(fp_line
			(start 0.12065 -0.2794)
			(end 0.12065 -0.3048)
			(stroke
				(width 0.1)
				(type default)
			)
			(layer "F.Fab")
		)
		(fp_line
			(start 0.67945 -0.3048)
			(end 0.67945 0.3048)
			(stroke
				(width 0.1)
				(type default)
			)
			(layer "F.Fab")
		)
		(fp_line
			(start 0.67945 0.3048)
			(end 0.120396 0.3048)
			(stroke
				(width 0.1)
				(type default)
			)
			(layer "F.Fab")
		)
		(pad "1" smd circle
			(at -0.40005 0)
			(size 0 0)
			(layers "F.Cu" "F.Mask" "F.Paste")
			(net "SVID_ALERT0_CPU1_R_N")
		)
		(pad "2" smd circle
			(at 0.40005 0)
			(size 0 0)
			(layers "F.Cu" "F.Mask" "F.Paste")
			(net "SVID_ALERT_PVCCIN_CPU1_R")
		)
	)
)
